# BASEBOARD_FAB2 (Tioga Pass) — schematic netlist excerpt (pin names and nets, part order shuffled) for the footprints in the layout excerpt that follows; sources: Cadence DE-HDL packaged netlist, KiCad conversion of Wiwynn_Tioga_Pass_MB.brd

R2R10  RES  33.2 1% CHIP  pkg 0402  page 157 : A = FP_NMI_BTN_R_N ; B = FP_NMI_BTN_N
C25W10  CAP_A  0.01UF 25V 10% X7R  pkg 0402V  page 151 : A = P1V2_AUX_BMC ; B = BMC_M_VREFCA
R9G2  RES  75 1.0% CHIP  pkg 0402  page 141 : A = LED_LAN_2_R_N ; B = LED_LAN_2_N

(kicad_pcb
	(version 20260206)
	(generator "pcbnew")
	(generator_version "10.0")
	(general
		(thickness 1.6)
		(legacy_teardrops no)
	)
	(paper "A4")
	(title_block
		(title "Wiwynn_Tioga_Pass_MB.brd")
		(comment 1 "Tioga Pass / footprints 4408-4410 of 4770")
	)
	(layers
		(0 "F.Cu" signal "TOP")
		(4 "In1.Cu" signal "L2GND")
		(6 "In2.Cu" signal "L3")
		(8 "In3.Cu" signal "L4GND")
		(10 "In4.Cu" signal "L5")
		(12 "In5.Cu" signal "L6GND")
		(14 "In6.Cu" signal "L7VCC")
		(16 "In7.Cu" signal "L8VCC")
		(18 "In8.Cu" signal "L9GND")
		(20 "In9.Cu" signal "L10")
		(22 "In10.Cu" signal "L11GND")
		(24 "In11.Cu" signal "L12")
		(26 "In12.Cu" signal "L13GND")
		(2 "B.Cu" signal "BOTTOM")
		(9 "F.Adhes" user "F.Adhesive")
		(11 "B.Adhes" user "B.Adhesive")
		(13 "F.Paste" user "Package Geometry/Pastemask Top")
		(15 "B.Paste" user "Package Geometry/Pastemask Bottom")
		(5 "F.SilkS" user "Ref Des/Silkscreen Top")
		(7 "B.SilkS" user "Ref Des/Silkscreen Bottom")
		(1 "F.Mask" user "Board Geometry/Soldermask Top")
		(3 "B.Mask" user "Board Geometry/Soldermask Bottom")
		(17 "Dwgs.User" user "User.Drawings")
		(19 "Cmts.User" user "User.Comments")
		(21 "Eco1.User" user "User.Eco1")
		(23 "Eco2.User" user "User.Eco2")
		(25 "Edge.Cuts" user "Board Geometry/Outline")
		(27 "Margin" user)
		(31 "F.CrtYd" user "Package Geometry/Place Bound Top")
		(29 "B.CrtYd" user "Package Geometry/Place Bound Bottom")
		(35 "F.Fab" user "Ref Des/Assembly Top")
		(33 "B.Fab" user "Ref Des/Assembly Bottom")
	)
	(footprint ""
		(layer "B.Cu")
		(at 448.19189 -28.8036 -90)
		(property "Reference" "C25W10"
			(at 0.8382 -0.67818 270)
			(unlocked yes)
			(layer "B.SilkS")
			(effects
				(font
					(size 0.4064 0.254)
					(thickness 0.1524)
				)
				(justify left mirror)
			)
		)
		(property "Value" ""
			(at 0 0 90)
			(layer "B.Fab")
			(effects
				(font
					(size 1.27 1.27)
				)
				(justify mirror)
			)
		)
		(duplicate_pad_numbers_are_jumpers no)
		(fp_poly
			(pts
				(xy -0.3048 -0.1016) (xy -0.3048 0.9906) (xy 0.3048 0.9906) (xy 0.3048 -0.1016)
			)
			(stroke
				(width 0)
				(type default)
			)
			(fill no)
			(layer "B.CrtYd")
		)
		(fp_line
			(start -0.3048 0.9906)
			(end -0.3048 -0.1016)
			(stroke
				(width 0.1)
				(type default)
			)
			(layer "B.Fab")
		)
		(fp_line
			(start 0.3048 0.9906)
			(end -0.3048 0.9906)
			(stroke
				(width 0.1)
				(type default)
			)
			(layer "B.Fab")
		)
		(fp_line
			(start -0.3048 -0.1016)
			(end 0.3048 -0.1016)
			(stroke
				(width 0.1)
				(type default)
			)
			(layer "B.Fab")
		)
		(fp_line
			(start 0.3048 -0.1016)
			(end 0.3048 0.9906)
			(stroke
				(width 0.1)
				(type default)
			)
			(layer "B.Fab")
		)
		(pad "1" smd rect
			(at 0 0 90)
			(size 0.508 0.508)
			(layers "B.Cu" "B.Mask" "B.Paste")
			(net "P1V2_AUX_BMC")
		)
		(pad "2" smd rect
			(at 0 0.889 90)
			(size 0.508 0.508)
			(layers "B.Cu" "B.Mask" "B.Paste")
			(net "BMC_M_VREFCA")
		)
		(zone
			(layer "B.Cu")
			(hatch none 0.5)
			(connect_pads
				(clearance 0)
			)
			(min_thickness 0.25)
			(keepout
				(tracks not_allowed)
				(vias allowed)
				(pads allowed)
				(copperpour not_allowed)
				(footprints allowed)
			)
			(placement
				(enabled no)
				(sheetname "")
			)
			(fill
				(thermal_gap 0.5)
				(thermal_bridge_width 0.5)
				(island_removal_mode 0)
			)
			(polygon
				(pts
					(xy 447.55689 -28.5496) (xy 447.55689 -29.0576) (xy 447.93789 -29.0576) (xy 447.93789 -28.5496)
				)
			)
		)
		(zone
			(layer "B.Cu")
			(hatch none 0.5)
			(connect_pads
				(clearance 0)
			)
			(min_thickness 0.25)
			(keepout
				(tracks allowed)
				(vias not_allowed)
				(pads allowed)
				(copperpour not_allowed)
				(footprints allowed)
			)
			(placement
				(enabled no)
				(sheetname "")
			)
			(fill
				(thermal_gap 0.5)
				(thermal_bridge_width 0.5)
				(island_removal_mode 0)
			)
			(polygon
				(pts
					(xy 447.93789 -28.5496) (xy 447.93789 -29.0576) (xy 447.55689 -29.0576) (xy 447.55689 -28.5496)
				)
			)
		)
	)
	(footprint ""
		(layer "B.Cu")
		(at 408.1907 -14.7828 -90)
		(property "Reference" "R2R10"
			(at 0 0 90)
			(layer "B.SilkS")
			(hide yes)
			(effects
				(font
					(size 1.27 1.27)
				)
				(justify mirror)
			)
		)
		(property "Value" ""
			(at 0 0 90)
			(layer "B.Fab")
			(effects
				(font
					(size 1.27 1.27)
				)
				(justify mirror)
			)
		)
		(duplicate_pad_numbers_are_jumpers no)
		(fp_poly
			(pts
				(xy 0.2794 -0.1016) (xy -0.2794 -0.1016) (xy -0.2794 0.9906) (xy 0.2794 0.9906)
			)
			(stroke
				(width 0)
				(type default)
			)
			(fill no)
			(layer "B.CrtYd")
		)
		(fp_line
			(start -0.2794 0.9906)
			(end -0.2794 -0.1016)
			(stroke
				(width 0.1)
				(type default)
			)
			(layer "B.Fab")
		)
		(fp_line
			(start 0.2794 0.9906)
			(end -0.2794 0.9906)
			(stroke
				(width 0.1)
				(type default)
			)
			(layer "B.Fab")
		)
		(fp_line
			(start -0.2794 -0.1016)
			(end 0.2794 -0.1016)
			(stroke
				(width 0.1)
				(type default)
			)
			(layer "B.Fab")
		)
		(fp_line
			(start 0.2794 -0.1016)
			(end 0.2794 0.9906)
			(stroke
				(width 0.1)
				(type default)
			)
			(layer "B.Fab")
		)
		(pad "1" smd rect
			(at 0 0 90)
			(size 0.508 0.508)
			(layers "B.Cu" "B.Mask" "B.Paste")
			(net "FP_NMI_BTN_R_N")
		)
		(pad "2" smd rect
			(at 0 0.889 90)
			(size 0.508 0.508)
			(layers "B.Cu" "B.Mask" "B.Paste")
			(net "FP_NMI_BTN_N")
		)
		(zone
			(layer "B.Cu")
			(hatch none 0.5)
			(connect_pads
				(clearance 0)
			)
			(min_thickness 0.25)
			(keepout
				(tracks not_allowed)
				(vias allowed)
				(pads allowed)
				(copperpour not_allowed)
				(footprints allowed)
			)
			(placement
				(enabled no)
				(sheetname "")
			)
			(fill
				(thermal_gap 0.5)
				(thermal_bridge_width 0.5)
				(island_removal_mode 0)
			)
			(polygon
				(pts
					(xy 407.5557 -14.5288) (xy 407.5557 -15.0368) (xy 407.9367 -15.0368) (xy 407.9367 -14.5288)
				)
			)
		)
		(zone
			(layer "B.Cu")
			(hatch none 0.5)
			(connect_pads
				(clearance 0)
			)
			(min_thickness 0.25)
			(keepout
				(tracks allowed)
				(vias not_allowed)
				(pads allowed)
				(copperpour not_allowed)
				(footprints allowed)
			)
			(placement
				(enabled no)
				(sheetname "")
			)
			(fill
				(thermal_gap 0.5)
				(thermal_bridge_width 0.5)
				(island_removal_mode 0)
			)
			(polygon
				(pts
					(xy 407.9367 -14.5288) (xy 407.9367 -15.0368) (xy 407.5557 -15.0368) (xy 407.5557 -14.5288)
				)
			)
		)
	)
	(footprint ""
		(layer "B.Cu")
		(at 483.785164 -17.036542 90)
		(property "Reference" "R9G2"
			(at 0 0 90)
			(layer "B.SilkS")
			(hide yes)
			(effects
				(font
					(size 1.27 1.27)
				)
				(justify mirror)
			)
		)
		(property "Value" ""
			(at 0 0 90)
			(layer "B.Fab")
			(effects
				(font
					(size 1.27 1.27)
				)
				(justify mirror)
			)
		)
		(duplicate_pad_numbers_are_jumpers no)
		(fp_poly
			(pts
				(xy 0.2794 -0.1016) (xy -0.2794 -0.1016) (xy -0.2794 0.9906) (xy 0.2794 0.9906)
			)
			(stroke
				(width 0)
				(type default)
			)
			(fill no)
			(layer "B.CrtYd")
		)
		(fp_line
			(start 0.2794 -0.1016)
			(end 0.2794 0.9906)
			(stroke
				(width 0.1)
				(type default)
			)
			(layer "B.Fab")
		)
		(fp_line
			(start -0.2794 -0.1016)
			(end 0.2794 -0.1016)
			(stroke
				(width 0.1)
				(type default)
			)
			(layer "B.Fab")
		)
		(fp_line
			(start 0.2794 0.9906)
			(end -0.2794 0.9906)
			(stroke
				(width 0.1)
				(type default)
			)
			(layer "B.Fab")
		)
		(fp_line
			(start -0.2794 0.9906)
			(end -0.2794 -0.1016)
			(stroke
				(width 0.1)
				(type default)
			)
			(layer "B.Fab")
		)
		(pad "1" smd rect
			(at 0 0 270)
			(size 0.508 0.508)
			(layers "B.Cu" "B.Mask" "B.Paste")
			(net "LED_LAN_2_R_N")
		)
		(pad "2" smd rect
			(at 0 0.889 270)
			(size 0.508 0.508)
			(layers "B.Cu" "B.Mask" "B.Paste")
			(net "LED_LAN_2_N")
		)
		(zone
			(layer "B.Cu")
			(hatch none 0.5)
			(connect_pads
				(clearance 0)
			)
			(min_thickness 0.25)
			(keepout
				(tracks allowed)
				(vias not_allowed)
				(pads allowed)
				(copperpour not_allowed)
				(footprints allowed)
			)
			(placement
				(enabled no)
				(sheetname "")
			)
			(fill
				(thermal_gap 0.5)
				(thermal_bridge_width 0.5)
				(island_removal_mode 0)
			)
			(polygon
				(pts
					(xy 484.039164 -17.290542) (xy 484.039164 -16.782542) (xy 484.420164 -16.782542) (xy 484.420164 -17.290542)
				)
			)
		)
		(zone
			(layer "B.Cu")
			(hatch none 0.5)
			(connect_pads
				(clearance 0)
			)
			(min_thickness 0.25)
			(keepout
				(tracks not_allowed)
				(vias allowed)
				(pads allowed)
				(copperpour not_allowed)
				(footprints allowed)
			)
			(placement
				(enabled no)
				(sheetname "")
			)
			(fill
				(thermal_gap 0.5)
				(thermal_bridge_width 0.5)
				(island_removal_mode 0)
			)
			(polygon
				(pts
					(xy 484.420164 -17.290542) (xy 484.420164 -16.782542) (xy 484.039164 -16.782542) (xy 484.039164 -17.290542)
				)
			)
		)
	)
)
